(kicad_pcb
	(version 20260206)
	(generator "pcbnew")
	(generator_version "10.0")
	(general
		(thickness 1.6)
		(legacy_teardrops no)
	)
	(paper "A4")
	(title_block
		(title "v1-pdb — T6M_PDB_D_0927_0900.brd")
		(comment 1 "Open CloudServer (Microsoft) / footprints 240-244 of 321")
	)
	(layers
		(0 "F.Cu" signal "TOP")
		(4 "In1.Cu" signal "GND")
		(6 "In2.Cu" signal "IN1")
		(8 "In3.Cu" signal "VCC")
		(10 "In4.Cu" signal "VCC1")
		(12 "In5.Cu" signal "IN2")
		(14 "In6.Cu" signal "GND1")
		(2 "B.Cu" signal "BOTTOM")
		(9 "F.Adhes" user "F.Adhesive")
		(11 "B.Adhes" user "B.Adhesive")
		(13 "F.Paste" user "Package Geometry/Pastemask Top")
		(15 "B.Paste" user "Package Geometry/Pastemask Bottom")
		(5 "F.SilkS" user "Ref Des/Silkscreen Top")
		(7 "B.SilkS" user "Ref Des/Silkscreen Bottom")
		(1 "F.Mask" user "Board Geometry/Soldermask Top")
		(3 "B.Mask" user "Board Geometry/Soldermask Bottom")
		(17 "Dwgs.User" user "User.Drawings")
		(19 "Cmts.User" user "User.Comments")
		(21 "Eco1.User" user "User.Eco1")
		(23 "Eco2.User" user "User.Eco2")
		(25 "Edge.Cuts" user "Board Geometry/Outline")
		(27 "Margin" user)
		(31 "F.CrtYd" user "Package Geometry/Place Bound Top")
		(29 "B.CrtYd" user "Package Geometry/Place Bound Bottom")
		(35 "F.Fab" user "Ref Des/Assembly Top")
		(33 "B.Fab" user "Ref Des/Assembly Bottom")
	)
	(footprint ""
		(layer "F.Cu")
		(at 27.16911 -373.43207)
		(property "Reference" "R19"
			(at -3.196844 0.148336 0)
			(unlocked yes)
			(layer "F.SilkS")
			(effects
				(font
					(size 0.7874 0.5842)
					(thickness 0.1524)
				)
				(justify left)
			)
		)
		(property "Value" ""
			(at 0 0 0)
			(layer "F.Fab")
			(effects
				(font
					(size 1.27 1.27)
				)
			)
		)
		(duplicate_pad_numbers_are_jumpers no)
		(fp_line
			(start -0.7874 -0.4064)
			(end 0.7874 -0.4064)
			(stroke
				(width 0.1524)
				(type default)
			)
			(layer "F.SilkS")
		)
		(fp_line
			(start -0.7874 0.4064)
			(end -0.7874 -0.4064)
			(stroke
				(width 0.1524)
				(type default)
			)
			(layer "F.SilkS")
		)
		(fp_line
			(start 0.7874 -0.4064)
			(end 0.7874 0.4064)
			(stroke
				(width 0.1524)
				(type default)
			)
			(layer "F.SilkS")
		)
		(fp_line
			(start 0.7874 0.4064)
			(end -0.7874 0.4064)
			(stroke
				(width 0.1524)
				(type default)
			)
			(layer "F.SilkS")
		)
		(fp_poly
			(pts
				(xy -0.508 0.2794) (xy -0.508 0.2286) (xy -0.635 0.2286) (xy -0.635 -0.254) (xy -0.5334 -0.254)
				(xy -0.5334 -0.2794) (xy 0.5334 -0.2794) (xy 0.5334 -0.254) (xy 0.635 -0.254) (xy 0.635 0.254) (xy 0.5334 0.254)
				(xy 0.5334 0.2794)
			)
			(stroke
				(width 0)
				(type default)
			)
			(fill no)
			(layer "F.CrtYd")
		)
		(pad "1" smd rect
			(at 0.40005 0)
			(size 0.4572 0.508)
			(layers "F.Cu" "F.Mask" "F.Paste")
			(net "PSU5_REMOTE_N")
		)
		(pad "2" smd rect
			(at -0.40005 0)
			(size 0.4572 0.508)
			(layers "F.Cu" "F.Mask" "F.Paste")
			(net "GND")
		)
	)
	(footprint ""
		(layer "F.Cu")
		(at 26.102056 -276.12213)
		(property "Reference" "R75"
			(at -4.037838 -0.005334 0)
			(unlocked yes)
			(layer "F.SilkS")
			(effects
				(font
					(size 0.7874 0.5842)
					(thickness 0.1524)
				)
				(justify left)
			)
		)
		(property "Value" ""
			(at 0 0 0)
			(layer "F.Fab")
			(effects
				(font
					(size 1.27 1.27)
				)
			)
		)
		(duplicate_pad_numbers_are_jumpers no)
		(fp_line
			(start -0.7874 -0.4064)
			(end 0.7874 -0.4064)
			(stroke
				(width 0.1524)
				(type default)
			)
			(layer "F.SilkS")
		)
		(fp_line
			(start -0.7874 0.4064)
			(end -0.7874 -0.4064)
			(stroke
				(width 0.1524)
				(type default)
			)
			(layer "F.SilkS")
		)
		(fp_line
			(start 0.7874 -0.4064)
			(end 0.7874 0.4064)
			(stroke
				(width 0.1524)
				(type default)
			)
			(layer "F.SilkS")
		)
		(fp_line
			(start 0.7874 0.4064)
			(end -0.7874 0.4064)
			(stroke
				(width 0.1524)
				(type default)
			)
			(layer "F.SilkS")
		)
		(fp_poly
			(pts
				(xy -0.508 0.2794) (xy -0.508 0.2286) (xy -0.635 0.2286) (xy -0.635 -0.254) (xy -0.5334 -0.254)
				(xy -0.5334 -0.2794) (xy 0.5334 -0.2794) (xy 0.5334 -0.254) (xy 0.635 -0.254) (xy 0.635 0.254) (xy 0.5334 0.254)
				(xy 0.5334 0.2794)
			)
			(stroke
				(width 0)
				(type default)
			)
			(fill no)
			(layer "F.CrtYd")
		)
		(pad "1" smd rect
			(at 0.40005 0)
			(size 0.4572 0.508)
			(layers "F.Cu" "F.Mask" "F.Paste")
			(net "PSU4_PS_KILL")
		)
		(pad "2" smd rect
			(at -0.40005 0)
			(size 0.4572 0.508)
			(layers "F.Cu" "F.Mask" "F.Paste")
			(net "GND")
		)
	)
	(footprint ""
		(layer "F.Cu")
		(at 50.217578 -84.273644 180)
		(property "Reference" "CE4"
			(at 1.809242 -5.224018 0)
			(unlocked yes)
			(layer "F.SilkS")
			(effects
				(font
					(size 0.7874 0.5842)
					(thickness 0.1524)
				)
				(justify left)
			)
		)
		(property "Value" ""
			(at 0 0 180)
			(layer "F.Fab")
			(effects
				(font
					(size 1.27 1.27)
				)
			)
		)
		(duplicate_pad_numbers_are_jumpers no)
		(fp_line
			(start 0 -4.2672)
			(end 0 4.2672)
			(stroke
				(width 0.1524)
				(type default)
			)
			(layer "F.SilkS")
		)
		(fp_circle
			(center 0 0)
			(end -4.2672 0)
			(stroke
				(width 0.1524)
				(type default)
			)
			(fill no)
			(layer "F.SilkS")
		)
		(fp_poly
			(pts
				(arc
					(start 0 -4.2672)
					(mid 4.2672 0)
					(end 0 4.2672)
				)
			)
			(stroke
				(width 0)
				(type default)
			)
			(fill yes)
			(layer "F.SilkS")
		)
		(fp_poly
			(pts
				(xy -2.5146 -0.762) (xy -0.9906 -0.762) (xy -0.9906 0.762) (xy -2.5146 0.762)
			)
			(stroke
				(width 0)
				(type default)
			)
			(fill no)
			(layer "B.CrtYd")
		)
		(fp_poly
			(pts
				(arc
					(start 1.7526 0.762)
					(mid 2.291415 -0.538815)
					(end 0.9906 0)
				)
				(arc
					(start 0.9906 0.0254)
					(mid 1.206345 0.546255)
					(end 1.7272 0.762)
				)
			)
			(stroke
				(width 0)
				(type default)
			)
			(fill no)
			(layer "B.CrtYd")
		)
		(fp_poly
			(pts
				(arc
					(start -4.2672 0)
					(mid 4.2672 0)
					(end -4.2672 0)
				)
			)
			(stroke
				(width 0)
				(type default)
			)
			(fill no)
			(layer "F.CrtYd")
		)
		(fp_circle
			(center 0 0)
			(end -4.2672 0)
			(stroke
				(width 0.1)
				(type default)
			)
			(fill no)
			(layer "F.Fab")
		)
		(fp_text user "+"
			(at -3.604514 -3.626866 180)
			(unlocked yes)
			(layer "F.SilkS")
			(effects
				(font
					(size 0.7874 0.5842)
					(thickness 0.1524)
				)
				(justify left)
			)
		)
		(fp_text user "+"
			(at -5.6642 -0.34925 180)
			(unlocked yes)
			(layer "F.Fab")
			(effects
				(font
					(size 1.905 1.4224)
					(thickness 0.000001)
				)
				(justify left)
			)
		)
		(pad "1" thru_hole rect
			(at -1.75006 0 180)
			(size 1.397 1.397)
			(drill 0.9144)
			(layers "*.Cu" "*.Mask")
			(remove_unused_layers no)
			(net "P12V")
			(clearance 0.0127)
			(thermal_gap 0.0127)
			(padstack
				(mode front_inner_back)
				(layer "Inner"
					(shape circle)
					(size 1.397 1.397)
					(clearance 0.0127)
				)
				(layer "B.Cu"
					(shape rect)
					(size 1.397 1.397)
					(clearance 0.0127)
				)
			)
		)
		(pad "2" thru_hole circle
			(at 1.75006 0 180)
			(size 1.397 1.397)
			(drill 0.9144)
			(layers "*.Cu" "*.Mask")
			(remove_unused_layers no)
			(net "GND")
			(clearance 0.0127)
			(thermal_gap 0.0127)
		)
	)
	(footprint ""
		(layer "F.Cu")
		(at 73.914508 -104.75976 -90)
		(property "Reference" "C17"
			(at -2.68224 -0.080772 90)
			(unlocked yes)
			(layer "F.SilkS")
			(effects
				(font
					(size 0.7874 0.5842)
					(thickness 0.1524)
				)
				(justify left)
			)
		)
		(property "Value" ""
			(at 0 0 270)
			(layer "F.Fab")
			(effects
				(font
					(size 1.27 1.27)
				)
			)
		)
		(duplicate_pad_numbers_are_jumpers no)
		(fp_line
			(start -0.7874 0.4064)
			(end -0.7874 -0.4064)
			(stroke
				(width 0.1524)
				(type default)
			)
			(layer "F.SilkS")
		)
		(fp_line
			(start 0.7874 0.4064)
			(end -0.7874 0.4064)
			(stroke
				(width 0.1524)
				(type default)
			)
			(layer "F.SilkS")
		)
		(fp_line
			(start 0 0.381)
			(end 0 -0.381)
			(stroke
				(width 0.1524)
				(type default)
			)
			(layer "F.SilkS")
		)
		(fp_line
			(start -0.7874 -0.4064)
			(end 0.7874 -0.4064)
			(stroke
				(width 0.1524)
				(type default)
			)
			(layer "F.SilkS")
		)
		(fp_line
			(start 0.7874 -0.4064)
			(end 0.7874 0.4064)
			(stroke
				(width 0.1524)
				(type default)
			)
			(layer "F.SilkS")
		)
		(fp_poly
			(pts
				(xy -0.5334 0.254) (xy -0.635 0.254) (xy -0.635 0.2286) (xy -0.635 -0.254) (xy -0.5334 -0.254) (xy -0.5334 -0.2794)
				(xy 0.5334 -0.2794) (xy 0.5334 -0.254) (xy 0.635 -0.254) (xy 0.635 0.254) (xy 0.5334 0.254) (xy 0.5334 0.2794)
				(xy -0.508 0.2794) (xy -0.5334 0.2794)
			)
			(stroke
				(width 0)
				(type default)
			)
			(fill no)
			(layer "F.CrtYd")
		)
		(pad "1" smd rect
			(at 0.40005 0 270)
			(size 0.4572 0.508)
			(layers "F.Cu" "F.Mask" "F.Paste")
			(net "P12V")
		)
		(pad "2" smd rect
			(at -0.40005 0 270)
			(size 0.4572 0.508)
			(layers "F.Cu" "F.Mask" "F.Paste")
			(net "GND")
		)
	)
	(footprint ""
		(layer "F.Cu")
		(at 70.095364 -238.216694 -90)
		(property "Reference" "C36"
			(at 0.16256 -3.77825 90)
			(unlocked yes)
			(layer "F.SilkS")
			(effects
				(font
					(size 0.7874 0.5842)
					(thickness 0.1524)
				)
			)
		)
		(property "Value" ""
			(at 0 0 270)
			(layer "F.Fab")
			(effects
				(font
					(size 1.27 1.27)
				)
			)
		)
		(duplicate_pad_numbers_are_jumpers no)
		(fp_line
			(start -1.2954 0.5842)
			(end -1.2954 -0.5842)
			(stroke
				(width 0.1524)
				(type default)
			)
			(layer "F.SilkS")
		)
		(fp_line
			(start 1.2954 0.5842)
			(end -1.2954 0.5842)
			(stroke
				(width 0.1524)
				(type default)
			)
			(layer "F.SilkS")
		)
		(fp_line
			(start -1.2954 -0.5842)
			(end 1.2954 -0.5842)
			(stroke
				(width 0.1524)
				(type default)
			)
			(layer "F.SilkS")
		)
		(fp_line
			(start 0 -0.5842)
			(end 0 0.5842)
			(stroke
				(width 0.1524)
				(type default)
			)
			(layer "F.SilkS")
		)
		(fp_line
			(start 1.2954 -0.5842)
			(end 1.2954 0.5842)
			(stroke
				(width 0.1524)
				(type default)
			)
			(layer "F.SilkS")
		)
		(fp_poly
			(pts
				(xy 0.8636 -0.4572) (xy 0.8636 -0.3556) (xy 1.143 -0.3556) (xy 1.143 0.3556) (xy 0.8636 0.3556)
				(xy 0.8636 0.4572) (xy -0.8636 0.4572) (xy -0.8636 0.3556) (xy -1.143 0.3556) (xy -1.143 -0.3556)
				(xy -0.8636 -0.3556) (xy -0.8636 -0.4572)
			)
			(stroke
				(width 0)
				(type default)
			)
			(fill no)
			(layer "F.CrtYd")
		)
		(fp_line
			(start -0.884936 0.504952)
			(end -0.884936 -0.504952)
			(stroke
				(width 0.1)
				(type default)
			)
			(layer "F.Fab")
		)
		(fp_line
			(start 0.884936 0.504952)
			(end -0.884936 0.504952)
			(stroke
				(width 0.1)
				(type default)
			)
			(layer "F.Fab")
		)
		(fp_line
			(start -0.884936 -0.504952)
			(end 0.884936 -0.504952)
			(stroke
				(width 0.1)
				(type default)
			)
			(layer "F.Fab")
		)
		(fp_line
			(start 0.884936 -0.504952)
			(end 0.884936 0.504952)
			(stroke
				(width 0.1)
				(type default)
			)
			(layer "F.Fab")
		)
		(pad "1" smd rect
			(at 0.7366 0)
			(size 0.7112 0.8128)
			(layers "F.Cu" "F.Mask" "F.Paste")
			(net "P12V")
		)
		(pad "2" smd rect
			(at -0.7366 0)
			(size 0.7112 0.8128)
			(layers "F.Cu" "F.Mask" "F.Paste")
			(net "GND")
		)
	)
)
